(kicad_pcb
	(version 20260206)
	(generator "pcbnew")
	(generator_version "10.0")
	(general
		(thickness 1.6)
		(legacy_teardrops no)
	)
	(paper "A4")
	(title_block
		(title "01162023_DA0F0TEBIF0_F0T_Expander_BD_F_brd_V02_OCP.brd")
		(comment 1 "Grand Teton / footprints 7805-7813 of 9728")
	)
	(layers
		(0 "F.Cu" signal "TOP")
		(4 "In1.Cu" signal "GND")
		(6 "In2.Cu" signal "VCC")
		(8 "In3.Cu" signal "VCC1")
		(10 "In4.Cu" signal "GND1")
		(12 "In5.Cu" signal "IN1")
		(14 "In6.Cu" signal "GND2")
		(16 "In7.Cu" signal "IN2")
		(18 "In8.Cu" signal "GND3")
		(20 "In9.Cu" signal "IN3")
		(22 "In10.Cu" signal "GND4")
		(24 "In11.Cu" signal "IN4")
		(26 "In12.Cu" signal "GND5")
		(28 "In13.Cu" signal "IN5")
		(30 "In14.Cu" signal "GND6")
		(32 "In15.Cu" signal "IN6")
		(34 "In16.Cu" signal "GND7")
		(2 "B.Cu" signal "BOTTOM")
		(9 "F.Adhes" user "F.Adhesive")
		(11 "B.Adhes" user "B.Adhesive")
		(13 "F.Paste" user "Package Geometry/Pastemask Top")
		(15 "B.Paste" user "Package Geometry/Pastemask Bottom")
		(5 "F.SilkS" user "Ref Des/Silkscreen Top")
		(7 "B.SilkS" user "Ref Des/Silkscreen Bottom")
		(1 "F.Mask" user "Board Geometry/Soldermask Top")
		(3 "B.Mask" user "Board Geometry/Soldermask Bottom")
		(17 "Dwgs.User" user "User.Drawings")
		(19 "Cmts.User" user "User.Comments")
		(21 "Eco1.User" user "User.Eco1")
		(23 "Eco2.User" user "User.Eco2")
		(25 "Edge.Cuts" user "Board Geometry/Outline")
		(27 "Margin" user)
		(31 "F.CrtYd" user "Package Geometry/Place Bound Top")
		(29 "B.CrtYd" user "Package Geometry/Place Bound Bottom")
		(35 "F.Fab" user "Ref Des/Assembly Top")
		(33 "B.Fab" user "Ref Des/Assembly Bottom")
	)
	(footprint ""
		(layer "B.Cu")
		(at 291.46119 -205.776068 180)
		(property "Reference" "R1044"
			(at 0 0 0)
			(layer "B.SilkS")
			(hide yes)
			(effects
				(font
					(size 1.27 1.27)
				)
				(justify mirror)
			)
		)
		(property "Value" ""
			(at 0 0 0)
			(layer "B.Fab")
			(effects
				(font
					(size 1.27 1.27)
				)
				(justify mirror)
			)
		)
		(duplicate_pad_numbers_are_jumpers no)
		(fp_line
			(start 0.7874 0.4064)
			(end 0.7874 -0.4064)
			(stroke
				(width 0.1524)
				(type default)
			)
			(layer "B.SilkS")
		)
		(fp_line
			(start 0.7874 -0.4064)
			(end -0.7874 -0.4064)
			(stroke
				(width 0.1524)
				(type default)
			)
			(layer "B.SilkS")
		)
		(fp_line
			(start -0.7874 0.4064)
			(end 0.7874 0.4064)
			(stroke
				(width 0.1524)
				(type default)
			)
			(layer "B.SilkS")
		)
		(fp_line
			(start -0.7874 -0.4064)
			(end -0.7874 0.4064)
			(stroke
				(width 0.1524)
				(type default)
			)
			(layer "B.SilkS")
		)
		(fp_line
			(start 0.67945 0.3048)
			(end 0.67945 -0.305054)
			(stroke
				(width 0.1)
				(type default)
			)
			(layer "B.Fab")
		)
		(fp_line
			(start 0.67945 -0.305054)
			(end 0.12065 -0.305054)
			(stroke
				(width 0.1)
				(type default)
			)
			(layer "B.Fab")
		)
		(fp_line
			(start 0.12065 0.3048)
			(end 0.67945 0.3048)
			(stroke
				(width 0.1)
				(type default)
			)
			(layer "B.Fab")
		)
		(fp_line
			(start 0.12065 0.2794)
			(end 0.12065 0.3048)
			(stroke
				(width 0.1)
				(type default)
			)
			(layer "B.Fab")
		)
		(fp_line
			(start 0.12065 -0.2794)
			(end -0.12065 -0.2794)
			(stroke
				(width 0.1)
				(type default)
			)
			(layer "B.Fab")
		)
		(fp_line
			(start 0.12065 -0.305054)
			(end 0.12065 -0.2794)
			(stroke
				(width 0.1)
				(type default)
			)
			(layer "B.Fab")
		)
		(fp_line
			(start -0.120396 0.3048)
			(end -0.120396 0.2794)
			(stroke
				(width 0.1)
				(type default)
			)
			(layer "B.Fab")
		)
		(fp_line
			(start -0.120396 0.2794)
			(end 0.12065 0.2794)
			(stroke
				(width 0.1)
				(type default)
			)
			(layer "B.Fab")
		)
		(fp_line
			(start -0.12065 -0.2794)
			(end -0.12065 -0.3048)
			(stroke
				(width 0.1)
				(type default)
			)
			(layer "B.Fab")
		)
		(fp_line
			(start -0.12065 -0.3048)
			(end -0.67945 -0.3048)
			(stroke
				(width 0.1)
				(type default)
			)
			(layer "B.Fab")
		)
		(fp_line
			(start -0.67945 0.3048)
			(end -0.120396 0.3048)
			(stroke
				(width 0.1)
				(type default)
			)
			(layer "B.Fab")
		)
		(fp_line
			(start -0.67945 -0.3048)
			(end -0.67945 0.3048)
			(stroke
				(width 0.1)
				(type default)
			)
			(layer "B.Fab")
		)
		(pad "1" smd circle
			(at 0.40005 0)
			(size 0 0)
			(layers "B.Cu" "B.Mask" "B.Paste")
			(net "GND")
		)
		(pad "2" smd circle
			(at -0.40005 0)
			(size 0 0)
			(layers "B.Cu" "B.Mask" "B.Paste")
			(net "SPI_BIC1_MISO_LS23_DIR4")
		)
	)
	(footprint ""
		(layer "B.Cu")
		(at 39.699946 -288.774886 -90)
		(property "Reference" "R3434"
			(at 0 0 90)
			(layer "B.SilkS")
			(hide yes)
			(effects
				(font
					(size 1.27 1.27)
				)
				(justify mirror)
			)
		)
		(property "Value" ""
			(at 0 0 90)
			(layer "B.Fab")
			(effects
				(font
					(size 1.27 1.27)
				)
				(justify mirror)
			)
		)
		(duplicate_pad_numbers_are_jumpers no)
		(fp_line
			(start -0.7874 0.4064)
			(end 0.7874 0.4064)
			(stroke
				(width 0.1524)
				(type default)
			)
			(layer "B.SilkS")
		)
		(fp_line
			(start 0.7874 0.4064)
			(end 0.7874 -0.4064)
			(stroke
				(width 0.1524)
				(type default)
			)
			(layer "B.SilkS")
		)
		(fp_line
			(start -0.7874 -0.4064)
			(end -0.7874 0.4064)
			(stroke
				(width 0.1524)
				(type default)
			)
			(layer "B.SilkS")
		)
		(fp_line
			(start 0.7874 -0.4064)
			(end -0.7874 -0.4064)
			(stroke
				(width 0.1524)
				(type default)
			)
			(layer "B.SilkS")
		)
		(fp_line
			(start -0.67945 0.3048)
			(end -0.120396 0.3048)
			(stroke
				(width 0.1)
				(type default)
			)
			(layer "B.Fab")
		)
		(fp_line
			(start -0.120396 0.3048)
			(end -0.120396 0.2794)
			(stroke
				(width 0.1)
				(type default)
			)
			(layer "B.Fab")
		)
		(fp_line
			(start 0.12065 0.3048)
			(end 0.67945 0.3048)
			(stroke
				(width 0.1)
				(type default)
			)
			(layer "B.Fab")
		)
		(fp_line
			(start 0.67945 0.3048)
			(end 0.67945 -0.305054)
			(stroke
				(width 0.1)
				(type default)
			)
			(layer "B.Fab")
		)
		(fp_line
			(start -0.120396 0.2794)
			(end 0.12065 0.2794)
			(stroke
				(width 0.1)
				(type default)
			)
			(layer "B.Fab")
		)
		(fp_line
			(start 0.12065 0.2794)
			(end 0.12065 0.3048)
			(stroke
				(width 0.1)
				(type default)
			)
			(layer "B.Fab")
		)
		(fp_line
			(start -0.12065 -0.2794)
			(end -0.12065 -0.3048)
			(stroke
				(width 0.1)
				(type default)
			)
			(layer "B.Fab")
		)
		(fp_line
			(start 0.12065 -0.2794)
			(end -0.12065 -0.2794)
			(stroke
				(width 0.1)
				(type default)
			)
			(layer "B.Fab")
		)
		(fp_line
			(start -0.67945 -0.3048)
			(end -0.67945 0.3048)
			(stroke
				(width 0.1)
				(type default)
			)
			(layer "B.Fab")
		)
		(fp_line
			(start -0.12065 -0.3048)
			(end -0.67945 -0.3048)
			(stroke
				(width 0.1)
				(type default)
			)
			(layer "B.Fab")
		)
		(fp_line
			(start 0.12065 -0.305054)
			(end 0.12065 -0.2794)
			(stroke
				(width 0.1)
				(type default)
			)
			(layer "B.Fab")
		)
		(fp_line
			(start 0.67945 -0.305054)
			(end 0.12065 -0.305054)
			(stroke
				(width 0.1)
				(type default)
			)
			(layer "B.Fab")
		)
		(pad "1" smd circle
			(at 0.40005 0 90)
			(size 0 0)
			(layers "B.Cu" "B.Mask" "B.Paste")
			(net "SPI_PEX0_SDIO3_R")
		)
		(pad "2" smd circle
			(at -0.40005 0 90)
			(size 0 0)
			(layers "B.Cu" "B.Mask" "B.Paste")
			(net "SPI_PEX0_SDIO3")
		)
	)
	(footprint ""
		(layer "B.Cu")
		(at 61.549788 -288.299906 90)
		(property "Reference" "C2923"
			(at 0 0 90)
			(layer "B.SilkS")
			(hide yes)
			(effects
				(font
					(size 1.27 1.27)
				)
				(justify mirror)
			)
		)
		(property "Value" ""
			(at 0 0 90)
			(layer "B.Fab")
			(effects
				(font
					(size 1.27 1.27)
				)
				(justify mirror)
			)
		)
		(duplicate_pad_numbers_are_jumpers no)
		(fp_line
			(start 0.299974 -0.150114)
			(end -0.299974 -0.150114)
			(stroke
				(width 0.1)
				(type default)
			)
			(layer "B.Fab")
		)
		(fp_line
			(start -0.299974 -0.150114)
			(end -0.299974 0.150114)
			(stroke
				(width 0.1)
				(type default)
			)
			(layer "B.Fab")
		)
		(fp_line
			(start 0.299974 0.150114)
			(end 0.299974 -0.150114)
			(stroke
				(width 0.1)
				(type default)
			)
			(layer "B.Fab")
		)
		(fp_line
			(start -0.299974 0.150114)
			(end 0.299974 0.150114)
			(stroke
				(width 0.1)
				(type default)
			)
			(layer "B.Fab")
		)
		(pad "1" smd rect
			(at 0.2667 0 270)
			(size 0.3048 0.381)
			(layers "B.Cu" "B.Mask" "B.Paste")
			(net "P1V25_PEX0")
		)
		(pad "2" smd rect
			(at -0.2667 0 270)
			(size 0.3048 0.381)
			(layers "B.Cu" "B.Mask" "B.Paste")
			(net "GND")
		)
	)
	(footprint ""
		(layer "B.Cu")
		(at 187.149994 -293.52494 180)
		(property "Reference" "C3110"
			(at 0 0 0)
			(layer "B.SilkS")
			(hide yes)
			(effects
				(font
					(size 1.27 1.27)
				)
				(justify mirror)
			)
		)
		(property "Value" ""
			(at 0 0 0)
			(layer "B.Fab")
			(effects
				(font
					(size 1.27 1.27)
				)
				(justify mirror)
			)
		)
		(duplicate_pad_numbers_are_jumpers no)
		(fp_line
			(start 0.299974 0.150114)
			(end 0.299974 -0.150114)
			(stroke
				(width 0.1)
				(type default)
			)
			(layer "B.Fab")
		)
		(fp_line
			(start 0.299974 -0.150114)
			(end -0.299974 -0.150114)
			(stroke
				(width 0.1)
				(type default)
			)
			(layer "B.Fab")
		)
		(fp_line
			(start -0.299974 0.150114)
			(end 0.299974 0.150114)
			(stroke
				(width 0.1)
				(type default)
			)
			(layer "B.Fab")
		)
		(fp_line
			(start -0.299974 -0.150114)
			(end -0.299974 0.150114)
			(stroke
				(width 0.1)
				(type default)
			)
			(layer "B.Fab")
		)
		(pad "1" smd rect
			(at 0.2667 0)
			(size 0.3048 0.381)
			(layers "B.Cu" "B.Mask" "B.Paste")
			(net "P1V25_PEX1")
		)
		(pad "2" smd rect
			(at -0.2667 0)
			(size 0.3048 0.381)
			(layers "B.Cu" "B.Mask" "B.Paste")
			(net "GND")
		)
	)
	(footprint ""
		(layer "B.Cu")
		(at 67.751198 -305.399948 -90)
		(property "Reference" "C2980"
			(at 0 0 90)
			(layer "B.SilkS")
			(hide yes)
			(effects
				(font
					(size 1.27 1.27)
				)
				(justify mirror)
			)
		)
		(property "Value" ""
			(at 0 0 90)
			(layer "B.Fab")
			(effects
				(font
					(size 1.27 1.27)
				)
				(justify mirror)
			)
		)
		(duplicate_pad_numbers_are_jumpers no)
		(fp_line
			(start -0.299974 0.150114)
			(end 0.299974 0.150114)
			(stroke
				(width 0.1)
				(type default)
			)
			(layer "B.Fab")
		)
		(fp_line
			(start 0.299974 0.150114)
			(end 0.299974 -0.150114)
			(stroke
				(width 0.1)
				(type default)
			)
			(layer "B.Fab")
		)
		(fp_line
			(start -0.299974 -0.150114)
			(end -0.299974 0.150114)
			(stroke
				(width 0.1)
				(type default)
			)
			(layer "B.Fab")
		)
		(fp_line
			(start 0.299974 -0.150114)
			(end -0.299974 -0.150114)
			(stroke
				(width 0.1)
				(type default)
			)
			(layer "B.Fab")
		)
		(pad "1" smd rect
			(at 0.2667 0 90)
			(size 0.3048 0.381)
			(layers "B.Cu" "B.Mask" "B.Paste")
			(net "P1V25_SERDES_VDDPLL_PEX0")
		)
		(pad "2" smd rect
			(at -0.2667 0 90)
			(size 0.3048 0.381)
			(layers "B.Cu" "B.Mask" "B.Paste")
			(net "GND")
		)
	)
	(footprint ""
		(layer "B.Cu")
		(at 105.207562 -358.724708 90)
		(property "Reference" "R6378"
			(at 0 0 90)
			(layer "B.SilkS")
			(hide yes)
			(effects
				(font
					(size 1.27 1.27)
				)
				(justify mirror)
			)
		)
		(property "Value" ""
			(at 0 0 90)
			(layer "B.Fab")
			(effects
				(font
					(size 1.27 1.27)
				)
				(justify mirror)
			)
		)
		(duplicate_pad_numbers_are_jumpers no)
		(fp_line
			(start 0.7874 -0.4064)
			(end -0.7874 -0.4064)
			(stroke
				(width 0.1524)
				(type default)
			)
			(layer "B.SilkS")
		)
		(fp_line
			(start -0.7874 -0.4064)
			(end -0.7874 0.4064)
			(stroke
				(width 0.1524)
				(type default)
			)
			(layer "B.SilkS")
		)
		(fp_line
			(start 0.7874 0.4064)
			(end 0.7874 -0.4064)
			(stroke
				(width 0.1524)
				(type default)
			)
			(layer "B.SilkS")
		)
		(fp_line
			(start -0.7874 0.4064)
			(end 0.7874 0.4064)
			(stroke
				(width 0.1524)
				(type default)
			)
			(layer "B.SilkS")
		)
		(fp_line
			(start 0.67945 -0.305054)
			(end 0.12065 -0.305054)
			(stroke
				(width 0.1)
				(type default)
			)
			(layer "B.Fab")
		)
		(fp_line
			(start 0.12065 -0.305054)
			(end 0.12065 -0.2794)
			(stroke
				(width 0.1)
				(type default)
			)
			(layer "B.Fab")
		)
		(fp_line
			(start -0.12065 -0.3048)
			(end -0.67945 -0.3048)
			(stroke
				(width 0.1)
				(type default)
			)
			(layer "B.Fab")
		)
		(fp_line
			(start -0.67945 -0.3048)
			(end -0.67945 0.3048)
			(stroke
				(width 0.1)
				(type default)
			)
			(layer "B.Fab")
		)
		(fp_line
			(start 0.12065 -0.2794)
			(end -0.12065 -0.2794)
			(stroke
				(width 0.1)
				(type default)
			)
			(layer "B.Fab")
		)
		(fp_line
			(start -0.12065 -0.2794)
			(end -0.12065 -0.3048)
			(stroke
				(width 0.1)
				(type default)
			)
			(layer "B.Fab")
		)
		(fp_line
			(start 0.12065 0.2794)
			(end 0.12065 0.3048)
			(stroke
				(width 0.1)
				(type default)
			)
			(layer "B.Fab")
		)
		(fp_line
			(start -0.120396 0.2794)
			(end 0.12065 0.2794)
			(stroke
				(width 0.1)
				(type default)
			)
			(layer "B.Fab")
		)
		(fp_line
			(start 0.67945 0.3048)
			(end 0.67945 -0.305054)
			(stroke
				(width 0.1)
				(type default)
			)
			(layer "B.Fab")
		)
		(fp_line
			(start 0.12065 0.3048)
			(end 0.67945 0.3048)
			(stroke
				(width 0.1)
				(type default)
			)
			(layer "B.Fab")
		)
		(fp_line
			(start -0.120396 0.3048)
			(end -0.120396 0.2794)
			(stroke
				(width 0.1)
				(type default)
			)
			(layer "B.Fab")
		)
		(fp_line
			(start -0.67945 0.3048)
			(end -0.120396 0.3048)
			(stroke
				(width 0.1)
				(type default)
			)
			(layer "B.Fab")
		)
		(pad "1" smd circle
			(at 0.40005 0 270)
			(size 0 0)
			(layers "B.Cu" "B.Mask" "B.Paste")
			(net "CLK_100M_DB800ZL_PEX2_S3_R_DP")
		)
		(pad "2" smd circle
			(at -0.40005 0 270)
			(size 0 0)
			(layers "B.Cu" "B.Mask" "B.Paste")
			(net "CLK_100M_DB800ZL_PEX2_S3_DP")
		)
	)
	(footprint ""
		(layer "B.Cu")
		(at 302.299878 -288.774886 180)
		(property "Reference" "C3351"
			(at 0 0 0)
			(layer "B.SilkS")
			(hide yes)
			(effects
				(font
					(size 1.27 1.27)
				)
				(justify mirror)
			)
		)
		(property "Value" ""
			(at 0 0 0)
			(layer "B.Fab")
			(effects
				(font
					(size 1.27 1.27)
				)
				(justify mirror)
			)
		)
		(duplicate_pad_numbers_are_jumpers no)
		(fp_line
			(start 0.299974 0.150114)
			(end 0.299974 -0.150114)
			(stroke
				(width 0.1)
				(type default)
			)
			(layer "B.Fab")
		)
		(fp_line
			(start 0.299974 -0.150114)
			(end -0.299974 -0.150114)
			(stroke
				(width 0.1)
				(type default)
			)
			(layer "B.Fab")
		)
		(fp_line
			(start -0.299974 0.150114)
			(end 0.299974 0.150114)
			(stroke
				(width 0.1)
				(type default)
			)
			(layer "B.Fab")
		)
		(fp_line
			(start -0.299974 -0.150114)
			(end -0.299974 0.150114)
			(stroke
				(width 0.1)
				(type default)
			)
			(layer "B.Fab")
		)
		(pad "1" smd rect
			(at 0.2667 0)
			(size 0.3048 0.381)
			(layers "B.Cu" "B.Mask" "B.Paste")
			(net "P1V8_PEX")
		)
		(pad "2" smd rect
			(at -0.2667 0)
			(size 0.3048 0.381)
			(layers "B.Cu" "B.Mask" "B.Paste")
			(net "GND")
		)
	)
	(footprint ""
		(layer "B.Cu")
		(at 397.44904 -301.0154 180)
		(property "Reference" "C1873"
			(at 0 0 0)
			(layer "B.SilkS")
			(hide yes)
			(effects
				(font
					(size 1.27 1.27)
				)
				(justify mirror)
			)
		)
		(property "Value" ""
			(at 0 0 0)
			(layer "B.Fab")
			(effects
				(font
					(size 1.27 1.27)
				)
				(justify mirror)
			)
		)
		(duplicate_pad_numbers_are_jumpers no)
		(fp_line
			(start 0.299974 0.150114)
			(end 0.299974 -0.150114)
			(stroke
				(width 0.1)
				(type default)
			)
			(layer "B.Fab")
		)
		(fp_line
			(start 0.299974 -0.150114)
			(end -0.299974 -0.150114)
			(stroke
				(width 0.1)
				(type default)
			)
			(layer "B.Fab")
		)
		(fp_line
			(start -0.299974 0.150114)
			(end 0.299974 0.150114)
			(stroke
				(width 0.1)
				(type default)
			)
			(layer "B.Fab")
		)
		(fp_line
			(start -0.299974 -0.150114)
			(end -0.299974 0.150114)
			(stroke
				(width 0.1)
				(type default)
			)
			(layer "B.Fab")
		)
		(pad "1" smd rect
			(at 0.2667 0)
			(size 0.3048 0.381)
			(layers "B.Cu" "B.Mask" "B.Paste")
			(net "P0V8_PEX3")
		)
		(pad "2" smd rect
			(at -0.2667 0)
			(size 0.3048 0.381)
			(layers "B.Cu" "B.Mask" "B.Paste")
			(net "GND")
		)
	)
	(footprint ""
		(layer "B.Cu")
		(at 167.675052 -286.399732 90)
		(property "Reference" "C3144"
			(at 0 0 90)
			(layer "B.SilkS")
			(hide yes)
			(effects
				(font
					(size 1.27 1.27)
				)
				(justify mirror)
			)
		)
		(property "Value" ""
			(at 0 0 90)
			(layer "B.Fab")
			(effects
				(font
					(size 1.27 1.27)
				)
				(justify mirror)
			)
		)
		(duplicate_pad_numbers_are_jumpers no)
		(fp_line
			(start 0.299974 -0.150114)
			(end -0.299974 -0.150114)
			(stroke
				(width 0.1)
				(type default)
			)
			(layer "B.Fab")
		)
		(fp_line
			(start -0.299974 -0.150114)
			(end -0.299974 0.150114)
			(stroke
				(width 0.1)
				(type default)
			)
			(layer "B.Fab")
		)
		(fp_line
			(start 0.299974 0.150114)
			(end 0.299974 -0.150114)
			(stroke
				(width 0.1)
				(type default)
			)
			(layer "B.Fab")
		)
		(fp_line
			(start -0.299974 0.150114)
			(end 0.299974 0.150114)
			(stroke
				(width 0.1)
				(type default)
			)
			(layer "B.Fab")
		)
		(pad "1" smd rect
			(at 0.2667 0 270)
			(size 0.3048 0.381)
			(layers "B.Cu" "B.Mask" "B.Paste")
			(net "P1V25_SERDES_VDDPLL_PEX1")
		)
		(pad "2" smd rect
			(at -0.2667 0 270)
			(size 0.3048 0.381)
			(layers "B.Cu" "B.Mask" "B.Paste")
			(net "GND")
		)
	)
)
